(kicad_pcb
	(version 20260206)
	(generator "pcbnew")
	(generator_version "10.0")
	(general
		(thickness 1.6)
		(legacy_teardrops no)
	)
	(paper "A4")
	(title_block
		(title "01162023_DA0F0TEBIF0_F0T_Expander_BD_F_brd_V02_OCP.brd")
		(comment 1 "Grand Teton / footprints 4854-4860 of 9728")
	)
	(layers
		(0 "F.Cu" signal "TOP")
		(4 "In1.Cu" signal "GND")
		(6 "In2.Cu" signal "VCC")
		(8 "In3.Cu" signal "VCC1")
		(10 "In4.Cu" signal "GND1")
		(12 "In5.Cu" signal "IN1")
		(14 "In6.Cu" signal "GND2")
		(16 "In7.Cu" signal "IN2")
		(18 "In8.Cu" signal "GND3")
		(20 "In9.Cu" signal "IN3")
		(22 "In10.Cu" signal "GND4")
		(24 "In11.Cu" signal "IN4")
		(26 "In12.Cu" signal "GND5")
		(28 "In13.Cu" signal "IN5")
		(30 "In14.Cu" signal "GND6")
		(32 "In15.Cu" signal "IN6")
		(34 "In16.Cu" signal "GND7")
		(2 "B.Cu" signal "BOTTOM")
		(9 "F.Adhes" user "F.Adhesive")
		(11 "B.Adhes" user "B.Adhesive")
		(13 "F.Paste" user "Package Geometry/Pastemask Top")
		(15 "B.Paste" user "Package Geometry/Pastemask Bottom")
		(5 "F.SilkS" user "Ref Des/Silkscreen Top")
		(7 "B.SilkS" user "Ref Des/Silkscreen Bottom")
		(1 "F.Mask" user "Board Geometry/Soldermask Top")
		(3 "B.Mask" user "Board Geometry/Soldermask Bottom")
		(17 "Dwgs.User" user "User.Drawings")
		(19 "Cmts.User" user "User.Comments")
		(21 "Eco1.User" user "User.Eco1")
		(23 "Eco2.User" user "User.Eco2")
		(25 "Edge.Cuts" user "Board Geometry/Outline")
		(27 "Margin" user)
		(31 "F.CrtYd" user "Package Geometry/Place Bound Top")
		(29 "B.CrtYd" user "Package Geometry/Place Bound Bottom")
		(35 "F.Fab" user "Ref Des/Assembly Top")
		(33 "B.Fab" user "Ref Des/Assembly Bottom")
	)
	(footprint ""
		(layer "F.Cu")
		(at 8.45058 -71.443088 180)
		(property "Reference" "R5654"
			(at 0 0 180)
			(layer "F.SilkS")
			(hide yes)
			(effects
				(font
					(size 1.27 1.27)
				)
			)
		)
		(property "Value" ""
			(at 0 0 180)
			(layer "F.Fab")
			(effects
				(font
					(size 1.27 1.27)
				)
			)
		)
		(duplicate_pad_numbers_are_jumpers no)
		(fp_line
			(start 0.7874 0.4064)
			(end -0.7874 0.4064)
			(stroke
				(width 0.1524)
				(type default)
			)
			(layer "F.SilkS")
		)
		(fp_line
			(start 0.7874 -0.4064)
			(end 0.7874 0.4064)
			(stroke
				(width 0.1524)
				(type default)
			)
			(layer "F.SilkS")
		)
		(fp_line
			(start -0.7874 0.4064)
			(end -0.7874 -0.4064)
			(stroke
				(width 0.1524)
				(type default)
			)
			(layer "F.SilkS")
		)
		(fp_line
			(start -0.7874 -0.4064)
			(end 0.7874 -0.4064)
			(stroke
				(width 0.1524)
				(type default)
			)
			(layer "F.SilkS")
		)
		(fp_line
			(start 0.67945 0.3048)
			(end 0.120396 0.3048)
			(stroke
				(width 0.1)
				(type default)
			)
			(layer "F.Fab")
		)
		(fp_line
			(start 0.67945 -0.3048)
			(end 0.67945 0.3048)
			(stroke
				(width 0.1)
				(type default)
			)
			(layer "F.Fab")
		)
		(fp_line
			(start 0.12065 -0.2794)
			(end 0.12065 -0.3048)
			(stroke
				(width 0.1)
				(type default)
			)
			(layer "F.Fab")
		)
		(fp_line
			(start 0.12065 -0.3048)
			(end 0.67945 -0.3048)
			(stroke
				(width 0.1)
				(type default)
			)
			(layer "F.Fab")
		)
		(fp_line
			(start 0.120396 0.3048)
			(end 0.120396 0.2794)
			(stroke
				(width 0.1)
				(type default)
			)
			(layer "F.Fab")
		)
		(fp_line
			(start 0.120396 0.2794)
			(end -0.12065 0.2794)
			(stroke
				(width 0.1)
				(type default)
			)
			(layer "F.Fab")
		)
		(fp_line
			(start -0.12065 0.3048)
			(end -0.67945 0.3048)
			(stroke
				(width 0.1)
				(type default)
			)
			(layer "F.Fab")
		)
		(fp_line
			(start -0.12065 0.2794)
			(end -0.12065 0.3048)
			(stroke
				(width 0.1)
				(type default)
			)
			(layer "F.Fab")
		)
		(fp_line
			(start -0.12065 -0.2794)
			(end 0.12065 -0.2794)
			(stroke
				(width 0.1)
				(type default)
			)
			(layer "F.Fab")
		)
		(fp_line
			(start -0.12065 -0.305054)
			(end -0.12065 -0.2794)
			(stroke
				(width 0.1)
				(type default)
			)
			(layer "F.Fab")
		)
		(fp_line
			(start -0.67945 0.3048)
			(end -0.67945 -0.305054)
			(stroke
				(width 0.1)
				(type default)
			)
			(layer "F.Fab")
		)
		(fp_line
			(start -0.67945 -0.305054)
			(end -0.12065 -0.305054)
			(stroke
				(width 0.1)
				(type default)
			)
			(layer "F.Fab")
		)
		(pad "1" smd circle
			(at -0.40005 0 180)
			(size 0 0)
			(layers "F.Cu" "F.Mask" "F.Paste")
			(net "RST_SMB_SSD0_ISO_R_N")
		)
		(pad "2" smd circle
			(at 0.40005 0 180)
			(size 0 0)
			(layers "F.Cu" "F.Mask" "F.Paste")
			(net "RST_SMB_SSD0_ISO_N")
		)
	)
	(footprint ""
		(layer "F.Cu")
		(at 428.83963 -138.661648 180)
		(property "Reference" "R396"
			(at 0 0 180)
			(layer "F.SilkS")
			(hide yes)
			(effects
				(font
					(size 1.27 1.27)
				)
			)
		)
		(property "Value" ""
			(at 0 0 180)
			(layer "F.Fab")
			(effects
				(font
					(size 1.27 1.27)
				)
			)
		)
		(duplicate_pad_numbers_are_jumpers no)
		(fp_line
			(start 0.7874 0.4064)
			(end -0.7874 0.4064)
			(stroke
				(width 0.1524)
				(type default)
			)
			(layer "F.SilkS")
		)
		(fp_line
			(start 0.7874 -0.4064)
			(end 0.7874 0.4064)
			(stroke
				(width 0.1524)
				(type default)
			)
			(layer "F.SilkS")
		)
		(fp_line
			(start -0.7874 0.4064)
			(end -0.7874 -0.4064)
			(stroke
				(width 0.1524)
				(type default)
			)
			(layer "F.SilkS")
		)
		(fp_line
			(start -0.7874 -0.4064)
			(end 0.7874 -0.4064)
			(stroke
				(width 0.1524)
				(type default)
			)
			(layer "F.SilkS")
		)
		(fp_line
			(start 0.67945 0.3048)
			(end 0.120396 0.3048)
			(stroke
				(width 0.1)
				(type default)
			)
			(layer "F.Fab")
		)
		(fp_line
			(start 0.67945 -0.3048)
			(end 0.67945 0.3048)
			(stroke
				(width 0.1)
				(type default)
			)
			(layer "F.Fab")
		)
		(fp_line
			(start 0.12065 -0.2794)
			(end 0.12065 -0.3048)
			(stroke
				(width 0.1)
				(type default)
			)
			(layer "F.Fab")
		)
		(fp_line
			(start 0.12065 -0.3048)
			(end 0.67945 -0.3048)
			(stroke
				(width 0.1)
				(type default)
			)
			(layer "F.Fab")
		)
		(fp_line
			(start 0.120396 0.3048)
			(end 0.120396 0.2794)
			(stroke
				(width 0.1)
				(type default)
			)
			(layer "F.Fab")
		)
		(fp_line
			(start 0.120396 0.2794)
			(end -0.12065 0.2794)
			(stroke
				(width 0.1)
				(type default)
			)
			(layer "F.Fab")
		)
		(fp_line
			(start -0.12065 0.3048)
			(end -0.67945 0.3048)
			(stroke
				(width 0.1)
				(type default)
			)
			(layer "F.Fab")
		)
		(fp_line
			(start -0.12065 0.2794)
			(end -0.12065 0.3048)
			(stroke
				(width 0.1)
				(type default)
			)
			(layer "F.Fab")
		)
		(fp_line
			(start -0.12065 -0.2794)
			(end 0.12065 -0.2794)
			(stroke
				(width 0.1)
				(type default)
			)
			(layer "F.Fab")
		)
		(fp_line
			(start -0.12065 -0.305054)
			(end -0.12065 -0.2794)
			(stroke
				(width 0.1)
				(type default)
			)
			(layer "F.Fab")
		)
		(fp_line
			(start -0.67945 0.3048)
			(end -0.67945 -0.305054)
			(stroke
				(width 0.1)
				(type default)
			)
			(layer "F.Fab")
		)
		(fp_line
			(start -0.67945 -0.305054)
			(end -0.12065 -0.305054)
			(stroke
				(width 0.1)
				(type default)
			)
			(layer "F.Fab")
		)
		(pad "1" smd circle
			(at -0.40005 0 180)
			(size 0 0)
			(layers "F.Cu" "F.Mask" "F.Paste")
			(net "PRSNT_NIC7_N")
		)
		(pad "2" smd circle
			(at 0.40005 0 180)
			(size 0 0)
			(layers "F.Cu" "F.Mask" "F.Paste")
			(net "PRSNTB0_NIC7_N")
		)
	)
	(footprint ""
		(layer "F.Cu")
		(at 311.514744 -79.58201 90)
		(property "Reference" "R304"
			(at 0 0 90)
			(layer "F.SilkS")
			(hide yes)
			(effects
				(font
					(size 1.27 1.27)
				)
			)
		)
		(property "Value" ""
			(at 0 0 90)
			(layer "F.Fab")
			(effects
				(font
					(size 1.27 1.27)
				)
			)
		)
		(duplicate_pad_numbers_are_jumpers no)
		(fp_line
			(start 0.7874 -0.4064)
			(end 0.7874 0.4064)
			(stroke
				(width 0.1524)
				(type default)
			)
			(layer "F.SilkS")
		)
		(fp_line
			(start -0.7874 -0.4064)
			(end 0.7874 -0.4064)
			(stroke
				(width 0.1524)
				(type default)
			)
			(layer "F.SilkS")
		)
		(fp_line
			(start 0.7874 0.4064)
			(end -0.7874 0.4064)
			(stroke
				(width 0.1524)
				(type default)
			)
			(layer "F.SilkS")
		)
		(fp_line
			(start -0.7874 0.4064)
			(end -0.7874 -0.4064)
			(stroke
				(width 0.1524)
				(type default)
			)
			(layer "F.SilkS")
		)
		(fp_line
			(start -0.12065 -0.305054)
			(end -0.12065 -0.2794)
			(stroke
				(width 0.1)
				(type default)
			)
			(layer "F.Fab")
		)
		(fp_line
			(start -0.67945 -0.305054)
			(end -0.12065 -0.305054)
			(stroke
				(width 0.1)
				(type default)
			)
			(layer "F.Fab")
		)
		(fp_line
			(start 0.67945 -0.3048)
			(end 0.67945 0.3048)
			(stroke
				(width 0.1)
				(type default)
			)
			(layer "F.Fab")
		)
		(fp_line
			(start 0.12065 -0.3048)
			(end 0.67945 -0.3048)
			(stroke
				(width 0.1)
				(type default)
			)
			(layer "F.Fab")
		)
		(fp_line
			(start 0.12065 -0.2794)
			(end 0.12065 -0.3048)
			(stroke
				(width 0.1)
				(type default)
			)
			(layer "F.Fab")
		)
		(fp_line
			(start -0.12065 -0.2794)
			(end 0.12065 -0.2794)
			(stroke
				(width 0.1)
				(type default)
			)
			(layer "F.Fab")
		)
		(fp_line
			(start 0.120396 0.2794)
			(end -0.12065 0.2794)
			(stroke
				(width 0.1)
				(type default)
			)
			(layer "F.Fab")
		)
		(fp_line
			(start -0.12065 0.2794)
			(end -0.12065 0.3048)
			(stroke
				(width 0.1)
				(type default)
			)
			(layer "F.Fab")
		)
		(fp_line
			(start 0.67945 0.3048)
			(end 0.120396 0.3048)
			(stroke
				(width 0.1)
				(type default)
			)
			(layer "F.Fab")
		)
		(fp_line
			(start 0.120396 0.3048)
			(end 0.120396 0.2794)
			(stroke
				(width 0.1)
				(type default)
			)
			(layer "F.Fab")
		)
		(fp_line
			(start -0.12065 0.3048)
			(end -0.67945 0.3048)
			(stroke
				(width 0.1)
				(type default)
			)
			(layer "F.Fab")
		)
		(fp_line
			(start -0.67945 0.3048)
			(end -0.67945 -0.305054)
			(stroke
				(width 0.1)
				(type default)
			)
			(layer "F.Fab")
		)
		(pad "1" smd circle
			(at -0.40005 0 90)
			(size 0 0)
			(layers "F.Cu" "F.Mask" "F.Paste")
			(net "P3V3_NIC5")
		)
		(pad "2" smd circle
			(at 0.40005 0 90)
			(size 0 0)
			(layers "F.Cu" "F.Mask" "F.Paste")
			(net "HP_NIC5_PWRGD")
		)
	)
	(footprint ""
		(layer "F.Cu")
		(at 219.260674 -105.291382)
		(property "Reference" "C419"
			(at 0 0 0)
			(layer "F.SilkS")
			(hide yes)
			(effects
				(font
					(size 1.27 1.27)
				)
			)
		)
		(property "Value" ""
			(at 0 0 0)
			(layer "F.Fab")
			(effects
				(font
					(size 1.27 1.27)
				)
			)
		)
		(duplicate_pad_numbers_are_jumpers no)
		(fp_line
			(start -0.7874 -0.4064)
			(end 0.7874 -0.4064)
			(stroke
				(width 0.1524)
				(type default)
			)
			(layer "F.SilkS")
		)
		(fp_line
			(start -0.7874 0.4064)
			(end -0.7874 -0.4064)
			(stroke
				(width 0.1524)
				(type default)
			)
			(layer "F.SilkS")
		)
		(fp_line
			(start 0.7874 -0.4064)
			(end 0.7874 0.4064)
			(stroke
				(width 0.1524)
				(type default)
			)
			(layer "F.SilkS")
		)
		(fp_line
			(start 0.7874 0.4064)
			(end -0.7874 0.4064)
			(stroke
				(width 0.1524)
				(type default)
			)
			(layer "F.SilkS")
		)
		(fp_line
			(start -0.67945 -0.305054)
			(end -0.12065 -0.305054)
			(stroke
				(width 0.1)
				(type default)
			)
			(layer "F.Fab")
		)
		(fp_line
			(start -0.67945 0.3048)
			(end -0.67945 -0.305054)
			(stroke
				(width 0.1)
				(type default)
			)
			(layer "F.Fab")
		)
		(fp_line
			(start -0.12065 -0.305054)
			(end -0.12065 -0.2794)
			(stroke
				(width 0.1)
				(type default)
			)
			(layer "F.Fab")
		)
		(fp_line
			(start -0.12065 -0.2794)
			(end 0.12065 -0.2794)
			(stroke
				(width 0.1)
				(type default)
			)
			(layer "F.Fab")
		)
		(fp_line
			(start -0.12065 0.2794)
			(end -0.12065 0.3048)
			(stroke
				(width 0.1)
				(type default)
			)
			(layer "F.Fab")
		)
		(fp_line
			(start -0.12065 0.3048)
			(end -0.67945 0.3048)
			(stroke
				(width 0.1)
				(type default)
			)
			(layer "F.Fab")
		)
		(fp_line
			(start 0.120396 0.2794)
			(end -0.12065 0.2794)
			(stroke
				(width 0.1)
				(type default)
			)
			(layer "F.Fab")
		)
		(fp_line
			(start 0.120396 0.3048)
			(end 0.120396 0.2794)
			(stroke
				(width 0.1)
				(type default)
			)
			(layer "F.Fab")
		)
		(fp_line
			(start 0.12065 -0.3048)
			(end 0.67945 -0.3048)
			(stroke
				(width 0.1)
				(type default)
			)
			(layer "F.Fab")
		)
		(fp_line
			(start 0.12065 -0.2794)
			(end 0.12065 -0.3048)
			(stroke
				(width 0.1)
				(type default)
			)
			(layer "F.Fab")
		)
		(fp_line
			(start 0.67945 -0.3048)
			(end 0.67945 0.3048)
			(stroke
				(width 0.1)
				(type default)
			)
			(layer "F.Fab")
		)
		(fp_line
			(start 0.67945 0.3048)
			(end 0.120396 0.3048)
			(stroke
				(width 0.1)
				(type default)
			)
			(layer "F.Fab")
		)
		(pad "1" smd circle
			(at -0.40005 0)
			(size 0 0)
			(layers "F.Cu" "F.Mask" "F.Paste")
			(net "P12V_NIC3_R")
		)
		(pad "2" smd circle
			(at 0.40005 0)
			(size 0 0)
			(layers "F.Cu" "F.Mask" "F.Paste")
			(net "GND")
		)
	)
	(footprint ""
		(layer "F.Cu")
		(at 237.101888 -32.849312 90)
		(property "Reference" "R5686"
			(at 0 0 90)
			(layer "F.SilkS")
			(hide yes)
			(effects
				(font
					(size 1.27 1.27)
				)
			)
		)
		(property "Value" ""
			(at 0 0 90)
			(layer "F.Fab")
			(effects
				(font
					(size 1.27 1.27)
				)
			)
		)
		(duplicate_pad_numbers_are_jumpers no)
		(fp_line
			(start 0.7874 -0.4064)
			(end 0.7874 0.4064)
			(stroke
				(width 0.1524)
				(type default)
			)
			(layer "F.SilkS")
		)
		(fp_line
			(start -0.7874 -0.4064)
			(end 0.7874 -0.4064)
			(stroke
				(width 0.1524)
				(type default)
			)
			(layer "F.SilkS")
		)
		(fp_line
			(start 0.7874 0.4064)
			(end -0.7874 0.4064)
			(stroke
				(width 0.1524)
				(type default)
			)
			(layer "F.SilkS")
		)
		(fp_line
			(start -0.7874 0.4064)
			(end -0.7874 -0.4064)
			(stroke
				(width 0.1524)
				(type default)
			)
			(layer "F.SilkS")
		)
		(fp_line
			(start -0.12065 -0.305054)
			(end -0.12065 -0.2794)
			(stroke
				(width 0.1)
				(type default)
			)
			(layer "F.Fab")
		)
		(fp_line
			(start -0.67945 -0.305054)
			(end -0.12065 -0.305054)
			(stroke
				(width 0.1)
				(type default)
			)
			(layer "F.Fab")
		)
		(fp_line
			(start 0.67945 -0.3048)
			(end 0.67945 0.3048)
			(stroke
				(width 0.1)
				(type default)
			)
			(layer "F.Fab")
		)
		(fp_line
			(start 0.12065 -0.3048)
			(end 0.67945 -0.3048)
			(stroke
				(width 0.1)
				(type default)
			)
			(layer "F.Fab")
		)
		(fp_line
			(start 0.12065 -0.2794)
			(end 0.12065 -0.3048)
			(stroke
				(width 0.1)
				(type default)
			)
			(layer "F.Fab")
		)
		(fp_line
			(start -0.12065 -0.2794)
			(end 0.12065 -0.2794)
			(stroke
				(width 0.1)
				(type default)
			)
			(layer "F.Fab")
		)
		(fp_line
			(start 0.120396 0.2794)
			(end -0.12065 0.2794)
			(stroke
				(width 0.1)
				(type default)
			)
			(layer "F.Fab")
		)
		(fp_line
			(start -0.12065 0.2794)
			(end -0.12065 0.3048)
			(stroke
				(width 0.1)
				(type default)
			)
			(layer "F.Fab")
		)
		(fp_line
			(start 0.67945 0.3048)
			(end 0.120396 0.3048)
			(stroke
				(width 0.1)
				(type default)
			)
			(layer "F.Fab")
		)
		(fp_line
			(start 0.120396 0.3048)
			(end 0.120396 0.2794)
			(stroke
				(width 0.1)
				(type default)
			)
			(layer "F.Fab")
		)
		(fp_line
			(start -0.12065 0.3048)
			(end -0.67945 0.3048)
			(stroke
				(width 0.1)
				(type default)
			)
			(layer "F.Fab")
		)
		(fp_line
			(start -0.67945 0.3048)
			(end -0.67945 -0.305054)
			(stroke
				(width 0.1)
				(type default)
			)
			(layer "F.Fab")
		)
		(pad "1" smd circle
			(at -0.40005 0 90)
			(size 0 0)
			(layers "F.Cu" "F.Mask" "F.Paste")
			(net "RST_SMB_SSD8_ISO_R_N")
		)
		(pad "2" smd circle
			(at 0.40005 0 90)
			(size 0 0)
			(layers "F.Cu" "F.Mask" "F.Paste")
			(net "RST_SMB_SSD8_ISO_N")
		)
	)
	(footprint ""
		(layer "F.Cu")
		(at 261.023608 -306.366418 45)
		(property "Reference" "R1388"
			(at 0 0 45)
			(layer "F.SilkS")
			(hide yes)
			(effects
				(font
					(size 1.27 1.27)
				)
			)
		)
		(property "Value" ""
			(at 0 0 45)
			(layer "F.Fab")
			(effects
				(font
					(size 1.27 1.27)
				)
			)
		)
		(duplicate_pad_numbers_are_jumpers no)
		(fp_line
			(start -0.787389 -0.406267)
			(end 0.787389 -0.406267)
			(stroke
				(width 0.1524)
				(type default)
			)
			(layer "F.SilkS")
		)
		(fp_line
			(start -0.787389 0.406267)
			(end -0.787389 -0.406267)
			(stroke
				(width 0.1524)
				(type default)
			)
			(layer "F.SilkS")
		)
		(fp_line
			(start 0.787389 -0.406267)
			(end 0.787389 0.406267)
			(stroke
				(width 0.1524)
				(type default)
			)
			(layer "F.SilkS")
		)
		(fp_line
			(start 0.787389 0.406267)
			(end -0.787389 0.406267)
			(stroke
				(width 0.1524)
				(type default)
			)
			(layer "F.SilkS")
		)
		(fp_line
			(start -0.679446 -0.305149)
			(end -0.120695 -0.304969)
			(stroke
				(width 0.1)
				(type default)
			)
			(layer "F.Fab")
		)
		(fp_line
			(start -0.120695 -0.304969)
			(end -0.120695 -0.279466)
			(stroke
				(width 0.1)
				(type default)
			)
			(layer "F.Fab")
		)
		(fp_line
			(start -0.120695 -0.279466)
			(end 0.120695 -0.279466)
			(stroke
				(width 0.1)
				(type default)
			)
			(layer "F.Fab")
		)
		(fp_line
			(start -0.679446 0.30479)
			(end -0.679446 -0.305149)
			(stroke
				(width 0.1)
				(type default)
			)
			(layer "F.Fab")
		)
		(fp_line
			(start 0.120515 -0.30479)
			(end 0.679446 -0.30479)
			(stroke
				(width 0.1)
				(type default)
			)
			(layer "F.Fab")
		)
		(fp_line
			(start 0.120695 -0.279466)
			(end 0.120515 -0.30479)
			(stroke
				(width 0.1)
				(type default)
			)
			(layer "F.Fab")
		)
		(fp_line
			(start -0.120695 0.279466)
			(end -0.120515 0.30479)
			(stroke
				(width 0.1)
				(type default)
			)
			(layer "F.Fab")
		)
		(fp_line
			(start -0.120515 0.30479)
			(end -0.679446 0.30479)
			(stroke
				(width 0.1)
				(type default)
			)
			(layer "F.Fab")
		)
		(fp_line
			(start 0.679446 -0.30479)
			(end 0.679446 0.30479)
			(stroke
				(width 0.1)
				(type default)
			)
			(layer "F.Fab")
		)
		(fp_line
			(start 0.120335 0.279466)
			(end -0.120695 0.279466)
			(stroke
				(width 0.1)
				(type default)
			)
			(layer "F.Fab")
		)
		(fp_line
			(start 0.120515 0.30479)
			(end 0.120335 0.279466)
			(stroke
				(width 0.1)
				(type default)
			)
			(layer "F.Fab")
		)
		(fp_line
			(start 0.679446 0.30479)
			(end 0.120515 0.30479)
			(stroke
				(width 0.1)
				(type default)
			)
			(layer "F.Fab")
		)
		(pad "1" smd circle
			(at -0.40005 0 45)
			(size 0 0)
			(layers "F.Cu" "F.Mask" "F.Paste")
			(net "GND")
		)
		(pad "2" smd circle
			(at 0.40005 0 45)
			(size 0 0)
			(layers "F.Cu" "F.Mask" "F.Paste")
			(net "PEX2_DFT_IDDT")
		)
	)
	(footprint ""
		(layer "F.Cu")
		(at 315.586364 -350.098614 90)
		(property "Reference" "C553"
			(at 0 0 90)
			(layer "F.SilkS")
			(hide yes)
			(effects
				(font
					(size 1.27 1.27)
				)
			)
		)
		(property "Value" ""
			(at 0 0 90)
			(layer "F.Fab")
			(effects
				(font
					(size 1.27 1.27)
				)
			)
		)
		(duplicate_pad_numbers_are_jumpers no)
		(fp_line
			(start 0.299974 -0.150114)
			(end 0.299974 0.150114)
			(stroke
				(width 0.1)
				(type default)
			)
			(layer "F.Fab")
		)
		(fp_line
			(start -0.299974 -0.150114)
			(end 0.299974 -0.150114)
			(stroke
				(width 0.1)
				(type default)
			)
			(layer "F.Fab")
		)
		(fp_line
			(start 0.299974 0.150114)
			(end -0.299974 0.150114)
			(stroke
				(width 0.1)
				(type default)
			)
			(layer "F.Fab")
		)
		(fp_line
			(start -0.299974 0.150114)
			(end -0.299974 -0.150114)
			(stroke
				(width 0.1)
				(type default)
			)
			(layer "F.Fab")
		)
		(pad "1" smd rect
			(at -0.2667 0 90)
			(size 0.3048 0.381)
			(layers "F.Cu" "F.Mask" "F.Paste")
			(net "P5E_PEX2_STN6_TX_DP<110>")
		)
		(pad "2" smd rect
			(at 0.2667 0 90)
			(size 0.3048 0.381)
			(layers "F.Cu" "F.Mask" "F.Paste")
			(net "P5E_PEX2_STN6_TX_C_DP<110>")
		)
	)
)
